
INPUT-UNITS     INCHES

WHEEL     1

CIRCLE            28            D10
CIRCLE            32            D11
RECTANGLE         18        20   0.00000  D12
RECTANGLE         20        18   0.00000  D13
RECTANGLE         22        24   0.00000  D14
RECTANGLE         24        22   0.00000  D15
CIRCLE            52            D16
FLASH     TR48X62X15-45        0.00000  D17
SQUARE            48   0.00000            D18
CIRCLE            48            D19
SQUARE            52   0.00000            D20
CIRCLE            71            D21
FLASH     TR57X71X15-45        0.00000  D22
CIRCLE            41            D23
CIRCLE            61            D24
RECTANGLE         12        20   0.00000  D25
RECTANGLE         20        12   0.00000  D26
RECTANGLE         16        24   0.00000  D27
RECTANGLE         24        16   0.00000  D28
CIRCLE           111            D29
FLASH     TR107X121X25-45      0.00000  D30
CIRCLE           131            D31
CIRCLE           135            D32
FLASH     TR44X58X15-45        0.00000  D33
SQUARE            44   0.00000            D34
CIRCLE            44            D35
SQUARE            32   0.00000            D36
SQUARE            36   0.00000            D37
RECTANGLE         26        54   0.00000  D38
RECTANGLE         54        26   0.00000  D39
RECTANGLE         30        58   0.00000  D40
RECTANGLE         58        30   0.00000  D41
RECTANGLE         26        28   0.00000  D42
RECTANGLE         28        26   0.00000  D43
RECTANGLE         18        52   0.00000  D44
RECTANGLE         52        18   0.00000  D45
RECTANGLE         22        56   0.00000  D46
RECTANGLE         56        22   0.00000  D47
CIRCLE            20            D48
CIRCLE            24            D49
CIRCLE            26            D50
CIRCLE            30            D51
CIRCLE           146            D52
FLASH     TR142X156X40-45      0.00000  D53
CIRCLE           256            D54
CIRCLE           260            D55
CIRCLE           170            D56
FLASH     TR166X180X40-45      0.00000  D57
CIRCLE           178            D58
CIRCLE           221            D59
CIRCLE           315            D60
CIRCLE           182            D61
CIRCLE           319            D62
LINE             156            D63
OBLONG           156       219   0.00000  D64
OBLONG           219       156   0.00000  D65
FLASH     B142-205X156-219X40   0.00000  D66
LINE             126            D67
OBLONG           126       189   0.00000  D68
OBLONG           189       126   0.00000  D69
LINE             256            D70
OBLONG           256       319   0.00000  D71
OBLONG           319       256   0.00000  D72
RECTANGLE         24        42   0.00000  D73
RECTANGLE         42        24   0.00000  D74
RECTANGLE         28        46   0.00000  D75
RECTANGLE         46        28   0.00000  D76
RECTANGLE         22        40   0.00000  D77
RECTANGLE         40        22   0.00000  D78
CIRCLE            66            D79
FLASH     TR52X66X15-45        0.00000  D80
CIRCLE            36            D81
CIRCLE            56            D82
CIRCLE            97            D83
FLASH     TR83X97X25-45        0.00000  D84
CIRCLE            67            D85
CIRCLE            87            D86
CIRCLE            78            D87
FLASH     TR64X78X15-45        0.00000  D88
CIRCLE            68            D89
RECTANGLE         49       110   0.00000  D90
RECTANGLE        110        49   0.00000  D91
RECTANGLE         53       114   0.00000  D92
RECTANGLE        114        53   0.00000  D93
RECTANGLE         11        63   0.00000  D94
RECTANGLE         63        11   0.00000  D95
RECTANGLE         15        67   0.00000  D96
RECTANGLE         67        15   0.00000  D97
RECTANGLE         20        34   0.00000  D98
RECTANGLE         34        20   0.00000  D99
RECTANGLE         24        38   0.00000  D100
RECTANGLE         38        24   0.00000  D101
RECTANGLE         16        34   0.00000  D102
RECTANGLE         34        16   0.00000  D103
RECTANGLE         20        38   0.00000  D104
RECTANGLE         38        20   0.00000  D105
CIRCLE           125            D106
RECTANGLE         13        46   0.00000  D107
RECTANGLE         46        13   0.00000  D108
RECTANGLE         17        50   0.00000  D109
RECTANGLE         50        17   0.00000  D110
FLASH     TR_C5-ALL            0.00000  D111
CIRCLE            18            D112
CIRCLE            22            D113
RECTANGLE         46        69   0.00000  D114
RECTANGLE         69        46   0.00000  D115
RECTANGLE         50        73   0.00000  D116
RECTANGLE         73        50   0.00000  D117
SQUARE            79   0.00000            D118
SQUARE            83   0.00000            D119
RECTANGLE         59        79   0.00000  D120
RECTANGLE         79        59   0.00000  D121
RECTANGLE         63        83   0.00000  D122
RECTANGLE         83        63   0.00000  D123
RECTANGLE         25        40   0.00000  D124
RECTANGLE         40        25   0.00000  D125
RECTANGLE         29        44   0.00000  D126
RECTANGLE         44        29   0.00000  D127
RECTANGLE         24        28   0.00000  D128
RECTANGLE         28        24   0.00000  D129
RECTANGLE         28        32   0.00000  D130
RECTANGLE         32        28   0.00000  D131
RECTANGLE         36       115   0.00000  D132
RECTANGLE        115        36   0.00000  D133
RECTANGLE         40       119   0.00000  D134
RECTANGLE        119        40   0.00000  D135
RECTANGLE         11        26   0.00000  D136
RECTANGLE         26        11   0.00000  D137
RECTANGLE         15        30   0.00000  D138
RECTANGLE         30        15   0.00000  D139
RECTANGLE         28        42   0.00000  D140
RECTANGLE         42        28   0.00000  D141
RECTANGLE         16        20   0.00000  D142
RECTANGLE         20        16   0.00000  D143
RECTANGLE         20        24   0.00000  D144
RECTANGLE         24        20   0.00000  D145
RECTANGLE         11        28   0.00000  D146
RECTANGLE         28        11   0.00000  D147
RECTANGLE         15        32   0.00000  D148
RECTANGLE         32        15   0.00000  D149
RECTANGLE         18        23   0.00000  D150
RECTANGLE         23        18   0.00000  D151
RECTANGLE         18        27   0.00000  D152
RECTANGLE         27        18   0.00000  D153
RECTANGLE         10        25   0.00000  D154
RECTANGLE         25        10   0.00000  D155
CIRCLE            65            D156
SQUARE            61   0.00000            D157
SQUARE            65   0.00000            D158
RECTANGLE         17        24   0.00000  D159
RECTANGLE         24        17   0.00000  D160
RECTANGLE         21        28   0.00000  D161
RECTANGLE         28        21   0.00000  D162
FLASH     TR_C6-ALL            0.00000  D163
CIRCLE          78.5            D164
CIRCLE          43.5            D165
CIRCLE          31.5            D166
CIRCLE          39.5            D167
CIRCLE            85            D168
RECTANGLE         40       109   0.00000  D169
RECTANGLE        109        40   0.00000  D170
RECTANGLE         44       113   0.00000  D171
RECTANGLE        113        44   0.00000  D172
RECTANGLE         28        40   0.00000  D173
RECTANGLE         40        28   0.00000  D174
RECTANGLE         32        44   0.00000  D175
RECTANGLE         44        32   0.00000  D176
RECTANGLE         14        44   0.00000  D177
RECTANGLE         44        14   0.00000  D178
RECTANGLE         18        48   0.00000  D179
RECTANGLE         48        18   0.00000  D180
RECTANGLE         20        59   0.00000  D181
RECTANGLE         59        20   0.00000  D182
RECTANGLE         24        63   0.00000  D183
RECTANGLE         63        24   0.00000  D184
RECTANGLE         48        71   0.00000  D185
RECTANGLE         71        48   0.00000  D186
RECTANGLE         52        75   0.00000  D187
RECTANGLE         75        52   0.00000  D188
RECTANGLE         24        61   0.00000  D189
RECTANGLE         61        24   0.00000  D190
RECTANGLE         28        65   0.00000  D191
RECTANGLE         65        28   0.00000  D192
RECTANGLE         17        67   0.00000  D193
RECTANGLE         67        17   0.00000  D194
RECTANGLE         21        71   0.00000  D195
RECTANGLE         71        21   0.00000  D196
RECTANGLE         40        56   0.00000  D197
RECTANGLE         56        40   0.00000  D198
RECTANGLE         44        60   0.00000  D199
RECTANGLE         60        44   0.00000  D200
RECTANGLE         40        15   0.00000  D201
RECTANGLE         15        40   0.00000  D202
RECTANGLE         44        19   0.00000  D203
RECTANGLE         19        44   0.00000  D204
RECTANGLE         10        52   0.00000  D205
RECTANGLE         52        10   0.00000  D206
RECTANGLE         14        56   0.00000  D207
RECTANGLE         56        14   0.00000  D208
RECTANGLE         10        36   0.00000  D209
RECTANGLE         36        10   0.00000  D210
RECTANGLE         14        40   0.00000  D211
RECTANGLE         40        14   0.00000  D212
CIRCLE          14.5            D213
CIRCLE          18.5            D214
RECTANGLE          7        32   0.00000  D215
RECTANGLE         32         7   0.00000  D216
RECTANGLE         11        36   0.00000  D217
RECTANGLE         36        11   0.00000  D218
CIRCLE            39            D219
CIRCLE           118            D220
RECTANGLE        130       130   0.00000  D221
RECTANGLE        134       134   0.00000  D222
CIRCLE           144            D223
FLASH     TR140X154X40-45      0.00000  D224
CIRCLE           238            D225
CIRCLE           242            D226
CIRCLE           154            D227
FLASH     TR150X164X40-45      0.00000  D228
CIRCLE           237            D229
CIRCLE           241            D230
RECTANGLE         69       105   0.00000  D231
RECTANGLE        105        69   0.00000  D232
RECTANGLE         73       109   0.00000  D233
RECTANGLE        109        73   0.00000  D234
RECTANGLE         24        36   0.00000  D235
RECTANGLE         36        24   0.00000  D236
RECTANGLE         16        36   0.00000  D237
RECTANGLE         36        16   0.00000  D238
RECTANGLE         20        40   0.00000  D239
RECTANGLE         40        20   0.00000  D240
RECTANGLE         14        34   0.00000  D241
RECTANGLE         34        14   0.00000  D242
RECTANGLE         22        32   0.00000  D243
RECTANGLE         32        22   0.00000  D244
RECTANGLE         26        36   0.00000  D245
RECTANGLE         36        26   0.00000  D246
RECTANGLE         18        28   0.00000  D247
RECTANGLE         28        18   0.00000  D248
CIRCLE            16            D249
RECTANGLE         24        24   0.00000  D250
RECTANGLE         28        28   0.00000  D251
RECTANGLE         20        20   0.00000  D252
RECTANGLE         39        48   0.00000  D253
RECTANGLE         48        39   0.00000  D254
RECTANGLE         43        52   0.00000  D255
RECTANGLE         52        43   0.00000  D256
RECTANGLE         24        65   0.00000  D257
RECTANGLE         65        24   0.00000  D258
RECTANGLE         28        69   0.00000  D259
RECTANGLE         69        28   0.00000  D260
RECTANGLE         20        60   0.00000  D261
RECTANGLE         60        20   0.00000  D262
RECTANGLE         12        79   0.00000  D263
RECTANGLE         79        12   0.00000  D264
RECTANGLE         16        83   0.00000  D265
RECTANGLE         83        16   0.00000  D266
RECTANGLE         14        59   0.00000  D267
RECTANGLE         59        14   0.00000  D268
RECTANGLE         18        63   0.00000  D269
RECTANGLE         63        18   0.00000  D270
RECTANGLE         46        62   0.00000  D271
RECTANGLE         62        46   0.00000  D272
RECTANGLE         50        66   0.00000  D273
RECTANGLE         66        50   0.00000  D274
RECTANGLE         14        49   0.00000  D275
RECTANGLE         49        14   0.00000  D276
RECTANGLE         18        53   0.00000  D277
RECTANGLE         53        18   0.00000  D278
RECTANGLE         44        54   0.00000  D279
RECTANGLE         54        44   0.00000  D280
RECTANGLE         48        58   0.00000  D281
RECTANGLE         58        48   0.00000  D282
RECTANGLE         34        46   0.00000  D283
RECTANGLE         46        34   0.00000  D284
RECTANGLE         38        50   0.00000  D285
RECTANGLE         50        38   0.00000  D286
RECTANGLE         15        68   0.00000  D287
RECTANGLE         68        15   0.00000  D288
RECTANGLE         19        72   0.00000  D289
RECTANGLE         72        19   0.00000  D290
RECTANGLE         40        48   0.00000  D291
RECTANGLE         48        40   0.00000  D292
RECTANGLE         44        52   0.00000  D293
RECTANGLE         52        44   0.00000  D294
RECTANGLE         32        36   0.00000  D295
RECTANGLE         36        32   0.00000  D296
RECTANGLE         17        70   0.00000  D297
RECTANGLE         70        17   0.00000  D298
RECTANGLE         21        74   0.00000  D299
RECTANGLE         74        21   0.00000  D300
RECTANGLE         15        84   0.00000  D301
RECTANGLE         84        15   0.00000  D302
RECTANGLE         19        88   0.00000  D303
RECTANGLE         88        19   0.00000  D304
RECTANGLE         10        59   0.00000  D305
RECTANGLE         59        10   0.00000  D306
RECTANGLE         14        63   0.00000  D307
RECTANGLE         63        14   0.00000  D308
RECTANGLE         36        40   0.00000  D309
RECTANGLE         40        36   0.00000  D310
RECTANGLE         14        36   0.00000  D311
RECTANGLE         36        14   0.00000  D312
RECTANGLE         18        40   0.00000  D313
RECTANGLE         40        18   0.00000  D314
RECTANGLE         20        28   0.00000  D315
RECTANGLE         28        20   0.00000  D316
RECTANGLE         40        71   0.00000  D317
RECTANGLE         71        40   0.00000  D318
RECTANGLE         44        75   0.00000  D319
RECTANGLE         75        44   0.00000  D320
RECTANGLE         10        28   0.00000  D321
RECTANGLE         28        10   0.00000  D322
RECTANGLE         14        32   0.00000  D323
RECTANGLE         32        14   0.00000  D324
RECTANGLE         17        20   0.00000  D325
RECTANGLE         20        17   0.00000  D326
RECTANGLE         21        24   0.00000  D327
RECTANGLE         24        21   0.00000  D328
RECTANGLE         40        50   0.00000  D329
RECTANGLE         50        40   0.00000  D330
RECTANGLE         12        32   0.00000  D331
RECTANGLE         32        12   0.00000  D332
CIRCLE            34            D333
RECTANGLE         56       231   0.00000  D334
RECTANGLE        231        56   0.00000  D335
RECTANGLE         60       235   0.00000  D336
RECTANGLE        235        60   0.00000  D337
RECTANGLE         35       231   0.00000  D338
RECTANGLE        231        35   0.00000  D339
CIRCLE           155            D340
FLASH     TR141X155X40-45      0.00000  D341
CIRCLE           145            D342
RECTANGLE       84.8       130   0.00000  D343
RECTANGLE        130      84.8   0.00000  D344
RECTANGLE       88.8       134   0.00000  D345
RECTANGLE        134      88.8   0.00000  D346
LINE               6            D347
LINE               2            D348
LINE               1            D349
LINE              18            D350
LINE               4            D351
LINE               8            D352
LINE              10            D353
LINE              25            D354
LINE             4.6            D355
LINE              15            D356
LINE             5.6            D357
LINE             4.2            D358
LINE              12            D359
LINE              40            D360
LINE              14            D361
LINE              20            D362
LINE             3.3            D363
LINE              80            D364
LINE             200            D365
LINE             4.5            D366
LINE             5.4            D367
LINE              13            D368
LINE            2.52            D369
LINE              16            D370
LINE             3.4            D371
LINE             5.1            D372
LINE               7            D373
LINE             4.1            D374
LINE              11            D375
LINE               5            D376
LINE            3.39            D377
LINE          154.87            D378
LINE          127.02            D379

